# T6G (Grand Teton) — schematic netlist excerpt (pin names and nets, part order shuffled) for the footprints in the layout excerpt that follows; sources: Cadence DE-HDL packaged netlist, KiCad conversion of 04192023_DAF0TMB3IC0_F0TG_MB_C_brd_V02_OCP.brd

C948  Q_CAP_DIFFBUS  DIFF BUS_0.22UF 6.3V 20% X6S  pkg C0201  page 63 : \1\ = P5E_CPU0_P1_TX_C_DN<8> ; \2\ = P5E_CPU0_P1_TX_DN<8>
PR3824  Q_RES  4.53K 1% CHIP  pkg 0402LF  page 140 : A = P3V3_OCP_SENSE_2 ; B = GND
R3661  Q_RES  47K 0.1% EMPTY  pkg 0402LF  page 234 : A = GND ; B = RST_USB_HUB_R_N

(kicad_pcb
	(version 20260206)
	(generator "pcbnew")
	(generator_version "10.0")
	(general
		(thickness 1.6)
		(legacy_teardrops no)
	)
	(paper "A4")
	(title_block
		(title "04192023_DAF0TMB3IC0_F0TG_MB_C_brd_V02_OCP.brd")
		(comment 1 "Grand Teton / footprints 3951-3953 of 8354")
	)
	(layers
		(0 "F.Cu" signal "TOP")
		(4 "In1.Cu" signal "GND")
		(6 "In2.Cu" signal "IN1")
		(8 "In3.Cu" signal "GND1")
		(10 "In4.Cu" signal "IN2")
		(12 "In5.Cu" signal "GND2")
		(14 "In6.Cu" signal "IN3")
		(16 "In7.Cu" signal "GND3")
		(18 "In8.Cu" signal "VCC")
		(20 "In9.Cu" signal "VCC1")
		(22 "In10.Cu" signal "GND4")
		(24 "In11.Cu" signal "IN4")
		(26 "In12.Cu" signal "GND5")
		(28 "In13.Cu" signal "IN5")
		(30 "In14.Cu" signal "GND6")
		(32 "In15.Cu" signal "IN6")
		(34 "In16.Cu" signal "GND7")
		(2 "B.Cu" signal "BOTTOM")
		(9 "F.Adhes" user "F.Adhesive")
		(11 "B.Adhes" user "B.Adhesive")
		(13 "F.Paste" user "Package Geometry/Pastemask Top")
		(15 "B.Paste" user "Package Geometry/Pastemask Bottom")
		(5 "F.SilkS" user "Ref Des/Silkscreen Top")
		(7 "B.SilkS" user "Ref Des/Silkscreen Bottom")
		(1 "F.Mask" user "Board Geometry/Soldermask Top")
		(3 "B.Mask" user "Board Geometry/Soldermask Bottom")
		(17 "Dwgs.User" user "User.Drawings")
		(19 "Cmts.User" user "User.Comments")
		(21 "Eco1.User" user "User.Eco1")
		(23 "Eco2.User" user "User.Eco2")
		(25 "Edge.Cuts" user "Board Geometry/Outline")
		(27 "Margin" user)
		(31 "F.CrtYd" user "Package Geometry/Place Bound Top")
		(29 "B.CrtYd" user "Package Geometry/Place Bound Bottom")
		(35 "F.Fab" user "Ref Des/Assembly Top")
		(33 "B.Fab" user "Ref Des/Assembly Bottom")
	)
	(footprint ""
		(layer "F.Cu")
		(at 10.873486 -92.687648 90)
		(property "Reference" "R3661"
			(at 0 0 90)
			(layer "F.SilkS")
			(hide yes)
			(effects
				(font
					(size 1.27 1.27)
				)
			)
		)
		(property "Value" ""
			(at 0 0 90)
			(layer "F.Fab")
			(effects
				(font
					(size 1.27 1.27)
				)
			)
		)
		(duplicate_pad_numbers_are_jumpers no)
		(fp_line
			(start 0.7874 -0.4064)
			(end 0.7874 0.4064)
			(stroke
				(width 0.1524)
				(type default)
			)
			(layer "F.SilkS")
		)
		(fp_line
			(start -0.7874 -0.4064)
			(end 0.7874 -0.4064)
			(stroke
				(width 0.1524)
				(type default)
			)
			(layer "F.SilkS")
		)
		(fp_line
			(start 0.7874 0.4064)
			(end -0.7874 0.4064)
			(stroke
				(width 0.1524)
				(type default)
			)
			(layer "F.SilkS")
		)
		(fp_line
			(start -0.7874 0.4064)
			(end -0.7874 -0.4064)
			(stroke
				(width 0.1524)
				(type default)
			)
			(layer "F.SilkS")
		)
		(fp_line
			(start -0.12065 -0.305054)
			(end -0.12065 -0.2794)
			(stroke
				(width 0.1)
				(type default)
			)
			(layer "F.Fab")
		)
		(fp_line
			(start -0.67945 -0.305054)
			(end -0.12065 -0.305054)
			(stroke
				(width 0.1)
				(type default)
			)
			(layer "F.Fab")
		)
		(fp_line
			(start 0.67945 -0.3048)
			(end 0.67945 0.3048)
			(stroke
				(width 0.1)
				(type default)
			)
			(layer "F.Fab")
		)
		(fp_line
			(start 0.12065 -0.3048)
			(end 0.67945 -0.3048)
			(stroke
				(width 0.1)
				(type default)
			)
			(layer "F.Fab")
		)
		(fp_line
			(start 0.12065 -0.2794)
			(end 0.12065 -0.3048)
			(stroke
				(width 0.1)
				(type default)
			)
			(layer "F.Fab")
		)
		(fp_line
			(start -0.12065 -0.2794)
			(end 0.12065 -0.2794)
			(stroke
				(width 0.1)
				(type default)
			)
			(layer "F.Fab")
		)
		(fp_line
			(start 0.120396 0.2794)
			(end -0.12065 0.2794)
			(stroke
				(width 0.1)
				(type default)
			)
			(layer "F.Fab")
		)
		(fp_line
			(start -0.12065 0.2794)
			(end -0.12065 0.3048)
			(stroke
				(width 0.1)
				(type default)
			)
			(layer "F.Fab")
		)
		(fp_line
			(start 0.67945 0.3048)
			(end 0.120396 0.3048)
			(stroke
				(width 0.1)
				(type default)
			)
			(layer "F.Fab")
		)
		(fp_line
			(start 0.120396 0.3048)
			(end 0.120396 0.2794)
			(stroke
				(width 0.1)
				(type default)
			)
			(layer "F.Fab")
		)
		(fp_line
			(start -0.12065 0.3048)
			(end -0.67945 0.3048)
			(stroke
				(width 0.1)
				(type default)
			)
			(layer "F.Fab")
		)
		(fp_line
			(start -0.67945 0.3048)
			(end -0.67945 -0.305054)
			(stroke
				(width 0.1)
				(type default)
			)
			(layer "F.Fab")
		)
		(pad "1" smd circle
			(at -0.40005 0 90)
			(size 0 0)
			(layers "F.Cu" "F.Mask" "F.Paste")
			(net "GND")
		)
		(pad "2" smd circle
			(at 0.40005 0 90)
			(size 0 0)
			(layers "F.Cu" "F.Mask" "F.Paste")
			(net "RST_USB_HUB_R_N")
		)
	)
	(footprint ""
		(layer "F.Cu")
		(at 346.046044 -381.41783 -90)
		(property "Reference" "C948"
			(at 0 0 270)
			(layer "F.SilkS")
			(hide yes)
			(effects
				(font
					(size 1.27 1.27)
				)
			)
		)
		(property "Value" ""
			(at 0 0 270)
			(layer "F.Fab")
			(effects
				(font
					(size 1.27 1.27)
				)
			)
		)
		(duplicate_pad_numbers_are_jumpers no)
		(fp_line
			(start -0.299974 0.150114)
			(end -0.299974 -0.150114)
			(stroke
				(width 0.1)
				(type default)
			)
			(layer "F.Fab")
		)
		(fp_line
			(start 0.299974 0.150114)
			(end -0.299974 0.150114)
			(stroke
				(width 0.1)
				(type default)
			)
			(layer "F.Fab")
		)
		(fp_line
			(start -0.299974 -0.150114)
			(end 0.299974 -0.150114)
			(stroke
				(width 0.1)
				(type default)
			)
			(layer "F.Fab")
		)
		(fp_line
			(start 0.299974 -0.150114)
			(end 0.299974 0.150114)
			(stroke
				(width 0.1)
				(type default)
			)
			(layer "F.Fab")
		)
		(pad "1" smd rect
			(at -0.2667 0 270)
			(size 0.3048 0.381)
			(layers "F.Cu" "F.Mask" "F.Paste")
			(net "P5E_CPU0_P1_TX_C_DN<8>")
		)
		(pad "2" smd rect
			(at 0.2667 0 270)
			(size 0.3048 0.381)
			(layers "F.Cu" "F.Mask" "F.Paste")
			(net "P5E_CPU0_P1_TX_DN<8>")
		)
	)
	(footprint ""
		(layer "F.Cu")
		(at 95.26143 -57.18683)
		(property "Reference" "PR3824"
			(at 0 0 0)
			(layer "F.SilkS")
			(hide yes)
			(effects
				(font
					(size 1.27 1.27)
				)
			)
		)
		(property "Value" ""
			(at 0 0 0)
			(layer "F.Fab")
			(effects
				(font
					(size 1.27 1.27)
				)
			)
		)
		(duplicate_pad_numbers_are_jumpers no)
		(fp_line
			(start -0.7874 -0.4064)
			(end 0.7874 -0.4064)
			(stroke
				(width 0.1524)
				(type default)
			)
			(layer "F.SilkS")
		)
		(fp_line
			(start -0.7874 0.4064)
			(end -0.7874 -0.4064)
			(stroke
				(width 0.1524)
				(type default)
			)
			(layer "F.SilkS")
		)
		(fp_line
			(start 0.7874 -0.4064)
			(end 0.7874 0.4064)
			(stroke
				(width 0.1524)
				(type default)
			)
			(layer "F.SilkS")
		)
		(fp_line
			(start 0.7874 0.4064)
			(end -0.7874 0.4064)
			(stroke
				(width 0.1524)
				(type default)
			)
			(layer "F.SilkS")
		)
		(fp_line
			(start -0.67945 -0.305054)
			(end -0.12065 -0.305054)
			(stroke
				(width 0.1)
				(type default)
			)
			(layer "F.Fab")
		)
		(fp_line
			(start -0.67945 0.3048)
			(end -0.67945 -0.305054)
			(stroke
				(width 0.1)
				(type default)
			)
			(layer "F.Fab")
		)
		(fp_line
			(start -0.12065 -0.305054)
			(end -0.12065 -0.2794)
			(stroke
				(width 0.1)
				(type default)
			)
			(layer "F.Fab")
		)
		(fp_line
			(start -0.12065 -0.2794)
			(end 0.12065 -0.2794)
			(stroke
				(width 0.1)
				(type default)
			)
			(layer "F.Fab")
		)
		(fp_line
			(start -0.12065 0.2794)
			(end -0.12065 0.3048)
			(stroke
				(width 0.1)
				(type default)
			)
			(layer "F.Fab")
		)
		(fp_line
			(start -0.12065 0.3048)
			(end -0.67945 0.3048)
			(stroke
				(width 0.1)
				(type default)
			)
			(layer "F.Fab")
		)
		(fp_line
			(start 0.120396 0.2794)
			(end -0.12065 0.2794)
			(stroke
				(width 0.1)
				(type default)
			)
			(layer "F.Fab")
		)
		(fp_line
			(start 0.120396 0.3048)
			(end 0.120396 0.2794)
			(stroke
				(width 0.1)
				(type default)
			)
			(layer "F.Fab")
		)
		(fp_line
			(start 0.12065 -0.3048)
			(end 0.67945 -0.3048)
			(stroke
				(width 0.1)
				(type default)
			)
			(layer "F.Fab")
		)
		(fp_line
			(start 0.12065 -0.2794)
			(end 0.12065 -0.3048)
			(stroke
				(width 0.1)
				(type default)
			)
			(layer "F.Fab")
		)
		(fp_line
			(start 0.67945 -0.3048)
			(end 0.67945 0.3048)
			(stroke
				(width 0.1)
				(type default)
			)
			(layer "F.Fab")
		)
		(fp_line
			(start 0.67945 0.3048)
			(end 0.120396 0.3048)
			(stroke
				(width 0.1)
				(type default)
			)
			(layer "F.Fab")
		)
		(pad "1" smd circle
			(at -0.40005 0)
			(size 0 0)
			(layers "F.Cu" "F.Mask" "F.Paste")
			(net "P3V3_OCP_SENSE_2")
		)
		(pad "2" smd circle
			(at 0.40005 0)
			(size 0 0)
			(layers "F.Cu" "F.Mask" "F.Paste")
			(net "GND")
		)
	)
)
